FILE_TYPE = CONNECTIVITY;
{Allegro Design Entry HDL 16.6-p007 (v16-6-112F) 10/10/2012}
"PAGE_NUMBER" = 253;
0"NC";
1"GND\g";
2"P5V_STBY\g";
3"GND\g";
4"GND\g";
5"P5V_STBY_USBC";
6"USB3_P01_FB_TXP";
7"USB3_P01_FB_RXP";
8"USB3_P01_FB_TXN";
9"USB3_P01_FB_RXN";
10"USB3_P01_RXP";
11"USB3_P01_C_TXN";
12"USB3_P01_RXN";
13"USB3_P01_TXP";
14"USB3_P01_TXN";
15"USB3_P01_C_TXP";
%"CHOKE_4PIN"
"2","(-5300,2150)","0","mstr_discrete","I11";
;
CDS_SEC"1"
CDS_LOCATION"L30W2"
PART_NUMBER"752402-028"
VALUE"67 OHM"
MATERIAL"EMPTY"
LOCATION"L30W2"
CDS_LMAN_SYM_OUTLINE"-200,150,150,-150"
CDS_LIB"mstr_discrete"
SEC_TYPE"SM_B"
SEC"1"
PACK_TYPE"SM_B";
"1"
$PN"1"15;
"4"
$PN"4"11;
"2"
$PN"2"6;
"3"
$PN"3"8;
%"RES"
"1","(-5350,3950)","0","mstr_discrete","I12";
;
CDS_SEC"1"
CDS_LOCATION"R30W2"
VALUE"0.0"
MATERIAL"CHIP"
PART_NUMBER"G21497-005"
TOLERANCE"5%"
WATTAGE"1/16W"
PACK_TYPE"0402"
LOCATION"R30W2"
ROOM"PROC_SIDEBAND"
SEC"1"
CDS_LIB"mstr_discrete"
SEC_TYPE"0402"
BOM_COST"PROC";
"B"
$PN"2"7;
"A"
$PN"1"10;
%"RES"
"1","(-5350,3000)","0","mstr_discrete","I13";
;
CDS_SEC"1"
CDS_LOCATION"R30W1"
LOCATION"R30W1"
VALUE"0.0"
PACK_TYPE"0402"
WATTAGE"1/16W"
TOLERANCE"5%"
PART_NUMBER"G21497-005"
MATERIAL"CHIP"
ROOM"PROC_SIDEBAND"
SEC"1"
CDS_LIB"mstr_discrete"
SEC_TYPE"0402"
BOM_COST"PROC";
"B"
$PN"2"9;
"A"
$PN"1"12;
%"RES"
"1","(-5350,2700)","0","mstr_discrete","I14";
;
CDS_SEC"1"
CDS_LOCATION"R30W4"
PART_NUMBER"G21497-005"
WATTAGE"1/16W"
MATERIAL"CHIP"
PACK_TYPE"0402"
TOLERANCE"5%"
LOCATION"R30W4"
VALUE"0.0"
BOM_COST"PROC"
SEC_TYPE"0402"
CDS_LIB"mstr_discrete"
SEC"1"
ROOM"PROC_SIDEBAND";
"B"
$PN"2"6;
"A"
$PN"1"15;
%"RES"
"1","(-5350,1750)","0","mstr_discrete","I15";
;
CDS_SEC"1"
CDS_LOCATION"R30W3"
LOCATION"R30W3"
PART_NUMBER"G21497-005"
TOLERANCE"5%"
MATERIAL"CHIP"
PACK_TYPE"0402"
WATTAGE"1/16W"
VALUE"0.0"
BOM_COST"PROC"
SEC_TYPE"0402"
CDS_LIB"mstr_discrete"
SEC"1"
ROOM"PROC_SIDEBAND";
"B"
$PN"2"8;
"A"
$PN"1"11;
%"CHOKE_4PIN"
"2","(-5300,3400)","0","mstr_discrete","I16";
;
CDS_SEC"1"
CDS_LOCATION"L30W1"
PART_NUMBER"752402-028"
LOCATION"L30W1"
VALUE"67 OHM"
MATERIAL"EMPTY"
CDS_LMAN_SYM_OUTLINE"-200,150,150,-150"
CDS_LIB"mstr_discrete"
SEC_TYPE"SM_B"
SEC"1"
PACK_TYPE"SM_B";
"1"
$PN"1"10;
"4"
$PN"4"12;
"2"
$PN"2"7;
"3"
$PN"3"9;
%"CAP_A"
"1","(-6275,2250)","1","dev_discrete","I19";
;
PART_NUMBER"A36096-030"
VOLTAGE"16V"
VALUE"0.1UF"
LOCATION"C30W2"
TOLERANCE"10%"
PACK_TYPE"0402V"
MATERIAL"X7R"
CDS_LOCATION"C30W2"
ROOM"PROC_SIDEBAND"
BOM_COST"PROC_SIDEBAND"
CDS_LIB"dev_discrete"
CDS_SEC"1"
SEC_TYPE"0402V"
SEC"1";
"B"
$PN"2"15;
"A"
$PN"1"13;
%"CAP_A"
"1","(-6275,2050)","1","dev_discrete","I20";
;
PACK_TYPE"0402V"
TOLERANCE"10%"
VALUE"0.1UF"
MATERIAL"X7R"
LOCATION"C30W1"
VOLTAGE"16V"
PART_NUMBER"A36096-030"
CDS_LOCATION"C30W1"
ROOM"PROC_SIDEBAND"
BOM_COST"PROC_SIDEBAND"
CDS_LIB"dev_discrete"
CDS_SEC"1"
SEC_TYPE"0402V"
SEC"1";
"B"
$PN"2"11;
"A"
$PN"1"14;
%"SKT-USB32-8-GP"
"1","(-1750,3775)","0","w_hdl","I26";
;
CDS_SEC"1"
CDS_LOCATION"J30W1"
VALUE"SKT-USB32-8-GP"
LOCATION"J30W1"
GROUP"NO_KR"
CDS_LMAN_SYM_OUTLINE"-250,675,250,-675"
CDS_LIB"w_hdl"
PART_NUMBER"062.10009.0621"
SEC_TYPE"SOCKET-G4"
SEC"1"
PACK_TYPE"SOCKET-G4";
"GND<3>"
$PN"B12"1;
"GND<2>"
$PN"B1"1;
"GND<1>"
$PN"A12"1;
"GND<0>"
$PN"A1"1;
"PTH8"
$PN"PTH8"1;
"PTH7"
$PN"PTH7"1;
"PTH6"
$PN"PTH6"1;
"PTH5"
$PN"PTH5"1;
"PTH4"
$PN"PTH4"1;
"PTH3"
$PN"PTH3"1;
"PTH2"
$PN"PTH2"1;
"PTH1"
$PN"PTH1"1;
"SBU2"
$PN"B8"0;
"SBU1"
$PN"A8"0;
"NP2"
$PN"NP2"0;
"NP1"
$PN"NP1"0;
"SSTXN2"
$PN"B3"0;
"SSTXP2"
$PN"B2"0;
"SSRXN2"
$PN"A10"0;
"SSRXP2"
$PN"A11"0;
"VBUS<3>"
$PN"B9"5;
"VBUS<2>"
$PN"B4"5;
"VBUS<1>"
$PN"A9"5;
"VBUS<0>"
$PN"A4"5;
"SSRXP1"
$PN"B11"7;
"SSRXN1"
$PN"B10"9;
"DN2"
$PN"B7"0;
"DP2"
$PN"B6"0;
"CC2"
$PN"B5"0;
"DN1"
$PN"A7"0;
"DP1"
$PN"A6"0;
"CC1"
$PN"A5"0;
"SSTXN1"
$PN"A3"8;
"SSTXP1"
$PN"A2"6;
%"GND"
"1","(-1200,3100)","0","mstr_symbols","I27";
;
CDS_LIB"mstr_symbols"
SIZE"1B"
VOLTAGE"0.0V"
BODY_TYPE"PLUMBING"
HDL_POWER"GND";
"A\NAC"1;
%"P5V_STBY"
"1","(-5650,4825)","0","mstr_symbols","I29";
;
CDS_LIB"mstr_symbols"
VOLTAGE"5.0V"
SIZE"1B"
BODY_TYPE"PLUMBING"
HDL_POWER"P5V_STBY";
"G\NAC"2;
%"SC22U16V5MX-4-GP"
"1","(-4550,4375)","0","w_hdl","I35";
;
LOCATION"C30W3"
TYPE"X6S"
ATTRIBUTE"22UF"
TOLERANCE"20%"
RATED"16V"
PACK_SIZE"0805"
VALUE"SC22U16V5MX-4-GP"
GROUP"NO_KR"
CDS_LOCATION"C30W3"
CDS_LMAN_SYM_OUTLINE"-50,25,50,-25"
CDS_LIB"w_hdl"
PART_NUMBER"078.22611.0811"
SEC_TYPE"SMD-BCG5"
SEC"1"
PACK_TYPE"SMD-BCG5"
CDS_SEC"1";
"2"
$PN"2"3;
"1"
$PN"1"5;
%"SC22U16V5MX-4-GP"
"1","(-4250,4375)","0","w_hdl","I36";
;
LOCATION"C30W4"
ATTRIBUTE"22UF"
RATED"16V"
TOLERANCE"20%"
TYPE"X6S"
VALUE"SC22U16V5MX-4-GP"
PACK_SIZE"0805"
GROUP"NO_KR"
CDS_LOCATION"C30W4"
CDS_LMAN_SYM_OUTLINE"-50,25,50,-25"
CDS_LIB"w_hdl"
PART_NUMBER"078.22611.0811"
SEC_TYPE"SMD-BCG5"
SEC"1"
PACK_TYPE"SMD-BCG5"
CDS_SEC"1";
"2"
$PN"2"3;
"1"
$PN"1"5;
%"SC22U16V5MX-4-GP"
"1","(-3650,4375)","0","w_hdl","I37";
;
PACK_SIZE"0805"
LOCATION"C30W6"
TYPE"X6S"
RATED"16V"
VALUE"SC22U16V5MX-4-GP"
TOLERANCE"20%"
ATTRIBUTE"22UF"
GROUP"NO_KR"
CDS_LMAN_SYM_OUTLINE"-50,25,50,-25"
CDS_LIB"w_hdl"
PART_NUMBER"078.22611.0811"
SEC_TYPE"SMD-BCG5"
SEC"1"
PACK_TYPE"SMD-BCG5"
CDS_SEC"1"
CDS_LOCATION"C30W6";
"2"
$PN"2"3;
"1"
$PN"1"5;
%"SC22U16V5MX-4-GP"
"1","(-3950,4375)","0","w_hdl","I38";
;
TOLERANCE"20%"
TYPE"X6S"
VALUE"SC22U16V5MX-4-GP"
PACK_SIZE"0805"
LOCATION"C30W5"
ATTRIBUTE"22UF"
RATED"16V"
GROUP"NO_KR"
CDS_LOCATION"C30W5"
CDS_SEC"1"
PACK_TYPE"SMD-BCG5"
SEC"1"
SEC_TYPE"SMD-BCG5"
PART_NUMBER"078.22611.0811"
CDS_LIB"w_hdl"
CDS_LMAN_SYM_OUTLINE"-50,25,50,-25";
"2"
$PN"2"3;
"1"
$PN"1"5;
%"SC22U16V5MX-4-GP"
"1","(-2750,4375)","0","w_hdl","I40";
;
TYPE"X6S"
PACK_SIZE"0805"
RATED"16V"
TOLERANCE"20%"
ATTRIBUTE"22UF"
LOCATION"C30W9"
VALUE"SC22U16V5MX-4-GP"
GROUP"NO_KR"
CDS_LOCATION"C30W9"
CDS_SEC"1"
PACK_TYPE"SMD-BCG5"
SEC"1"
SEC_TYPE"SMD-BCG5"
PART_NUMBER"078.22611.0811"
CDS_LIB"w_hdl"
CDS_LMAN_SYM_OUTLINE"-50,25,50,-25";
"2"
$PN"2"3;
"1"
$PN"1"5;
%"SC22U16V5MX-4-GP"
"1","(-3050,4375)","0","w_hdl","I41";
;
LOCATION"C30W8"
TOLERANCE"20%"
PACK_SIZE"0805"
TYPE"X6S"
RATED"16V"
ATTRIBUTE"22UF"
VALUE"SC22U16V5MX-4-GP"
GROUP"NO_KR"
CDS_LMAN_SYM_OUTLINE"-50,25,50,-25"
CDS_LIB"w_hdl"
PART_NUMBER"078.22611.0811"
SEC_TYPE"SMD-BCG5"
SEC"1"
PACK_TYPE"SMD-BCG5"
CDS_SEC"1"
CDS_LOCATION"C30W8";
"2"
$PN"2"3;
"1"
$PN"1"5;
%"SC22U16V5MX-4-GP"
"1","(-3350,4375)","0","w_hdl","I42";
;
RATED"16V"
TYPE"X6S"
PACK_SIZE"0805"
TOLERANCE"20%"
ATTRIBUTE"22UF"
VALUE"SC22U16V5MX-4-GP"
LOCATION"C30W7"
GROUP"NO_KR"
CDS_LOCATION"C30W7"
CDS_SEC"1"
PACK_TYPE"SMD-BCG5"
SEC"1"
SEC_TYPE"SMD-BCG5"
PART_NUMBER"078.22611.0811"
CDS_LIB"w_hdl"
CDS_LMAN_SYM_OUTLINE"-50,25,50,-25";
"2"
$PN"2"3;
"1"
$PN"1"5;
%"GND"
"1","(-2750,4000)","0","mstr_symbols","I43";
;
CDS_LIB"mstr_symbols"
SIZE"1B"
VOLTAGE"0.0V"
BODY_TYPE"PLUMBING"
HDL_POWER"GND";
"A\NAC"3;
%"POLYSW-1D1A6V-2-GP-U"
"1","(-5225,4675)","0","w_hdl","I44";
;
CDS_SEC"1"
CDS_LOCATION"F30W1"
LOCATION"F30W1"
GROUP"NO_KR"
VALUE"POLYSW-1D1A6V-2-GP-U"
CDS_LMAN_SYM_OUTLINE"-125,50,125,-50"
CDS_LIB"w_hdl"
PART_NUMBER"69.50007.D81"
SEC_TYPE"DISCRET-G7"
SEC"1"
PACK_TYPE"DISCRET-G7";
"2"
$PN"2"5;
"1"
$PN"1"2;
%"DIODEAC_DUAL_ARRAY"
"7","(-3300,2300)","0","mstr_discrete","I5";
;
CDS_SEC"1"
MATERIAL"IC"
PART_NUMBER"G18435-001"
LOCATION"CR30W1"
VALUE"ESD3V3U4ULC"
CDS_LOCATION"CR30W1"
BOM_COST"MIO_USB"
PACK_TYPE"SM9"
SEC_TYPE"SM9"
SEC"1"
ROOM"USB_REAR"
CDS_LIB"mstr_discrete";
"AC3"
$PN"5"7;
"AC2"
$PN"4"9;
"AC1"
$PN"2"6;
"AC0"
$PN"1"8;
"OUT3"
$PN"6"7;
"OUT2"
$PN"7"9;
"OUT1"
$PN"8"6;
"OUT0"
$PN"9"8;
"GND<0>"
$PN"3"4;
%"GND"
"1","(-2900,2050)","0","mstr_symbols","I9";
;
VOLTAGE"0.0V"
SIZE"1B"
CDS_LIB"mstr_symbols"
BODY_TYPE"PLUMBING"
HDL_POWER"GND";
"A\NAC"4;
END.
